# BASEBOARD_FAB2 (Tioga Pass) — schematic netlist excerpt (pin names and nets, part order shuffled) for the footprints in the layout excerpt that follows; sources: Cadence DE-HDL packaged netlist, KiCad conversion of Wiwynn_Tioga_Pass_MB.brd

R7A7  RES  10.0 1% CHIP  pkg 0402  page 218 : A = VSENSE_PVDDQ_DEF_P ; B = VR_PVDDQ_DEF_AVSP
C2A14  CAP_A  47UF 4V 20% X5R  pkg 0603V  page 228 : A = PVDDQ_KLM ; B = GND
C7C2  CAP  0.22UF 16V 10% X7R  pkg 0402  page 129 : A = DMI_CPU0_PCH_TX_DP<0> ; B = DMI_CPU0_PCH_TX_C_DP<0>

(kicad_pcb
	(version 20260206)
	(generator "pcbnew")
	(generator_version "10.0")
	(general
		(thickness 1.6)
		(legacy_teardrops no)
	)
	(paper "A4")
	(title_block
		(title "Wiwynn_Tioga_Pass_MB.brd")
		(comment 1 "Tioga Pass / footprints 907-909 of 4770")
	)
	(layers
		(0 "F.Cu" signal "TOP")
		(4 "In1.Cu" signal "L2GND")
		(6 "In2.Cu" signal "L3")
		(8 "In3.Cu" signal "L4GND")
		(10 "In4.Cu" signal "L5")
		(12 "In5.Cu" signal "L6GND")
		(14 "In6.Cu" signal "L7VCC")
		(16 "In7.Cu" signal "L8VCC")
		(18 "In8.Cu" signal "L9GND")
		(20 "In9.Cu" signal "L10")
		(22 "In10.Cu" signal "L11GND")
		(24 "In11.Cu" signal "L12")
		(26 "In12.Cu" signal "L13GND")
		(2 "B.Cu" signal "BOTTOM")
		(9 "F.Adhes" user "F.Adhesive")
		(11 "B.Adhes" user "B.Adhesive")
		(13 "F.Paste" user "Package Geometry/Pastemask Top")
		(15 "B.Paste" user "Package Geometry/Pastemask Bottom")
		(5 "F.SilkS" user "Ref Des/Silkscreen Top")
		(7 "B.SilkS" user "Ref Des/Silkscreen Bottom")
		(1 "F.Mask" user "Board Geometry/Soldermask Top")
		(3 "B.Mask" user "Board Geometry/Soldermask Bottom")
		(17 "Dwgs.User" user "User.Drawings")
		(19 "Cmts.User" user "User.Comments")
		(21 "Eco1.User" user "User.Eco1")
		(23 "Eco2.User" user "User.Eco2")
		(25 "Edge.Cuts" user "Board Geometry/Outline")
		(27 "Margin" user)
		(31 "F.CrtYd" user "Package Geometry/Place Bound Top")
		(29 "B.CrtYd" user "Package Geometry/Place Bound Bottom")
		(35 "F.Fab" user "Ref Des/Assembly Top")
		(33 "B.Fab" user "Ref Des/Assembly Bottom")
	)
	(footprint ""
		(layer "F.Cu")
		(at 368.554 -110.998 90)
		(property "Reference" "C7C2"
			(at 0 0 90)
			(layer "F.SilkS")
			(hide yes)
			(effects
				(font
					(size 1.27 1.27)
				)
			)
		)
		(property "Value" ""
			(at 0 0 90)
			(layer "F.Fab")
			(effects
				(font
					(size 1.27 1.27)
				)
			)
		)
		(duplicate_pad_numbers_are_jumpers no)
		(fp_poly
			(pts
				(xy 0.3048 -0.1016) (xy 0.3048 0.9906) (xy -0.3048 0.9906) (xy -0.3048 -0.1016)
			)
			(stroke
				(width 0)
				(type default)
			)
			(fill no)
			(layer "F.CrtYd")
		)
		(fp_line
			(start 0.3048 -0.1016)
			(end -0.3048 -0.1016)
			(stroke
				(width 0.1)
				(type default)
			)
			(layer "F.Fab")
		)
		(fp_line
			(start -0.3048 -0.1016)
			(end -0.3048 0.9906)
			(stroke
				(width 0.1)
				(type default)
			)
			(layer "F.Fab")
		)
		(fp_line
			(start 0.3048 0.9906)
			(end 0.3048 -0.1016)
			(stroke
				(width 0.1)
				(type default)
			)
			(layer "F.Fab")
		)
		(fp_line
			(start -0.3048 0.9906)
			(end 0.3048 0.9906)
			(stroke
				(width 0.1)
				(type default)
			)
			(layer "F.Fab")
		)
		(pad "1" smd rect
			(at 0 0 90)
			(size 0.508 0.508)
			(layers "F.Cu" "F.Mask" "F.Paste")
			(net "DMI_CPU0_PCH_TX_DP<0>")
		)
		(pad "2" smd rect
			(at 0 0.889 90)
			(size 0.508 0.508)
			(layers "F.Cu" "F.Mask" "F.Paste")
			(net "DMI_CPU0_PCH_TX_C_DP<0>")
		)
		(zone
			(layer "F.Cu")
			(hatch none 0.5)
			(connect_pads
				(clearance 0)
			)
			(min_thickness 0.25)
			(keepout
				(tracks allowed)
				(vias not_allowed)
				(pads allowed)
				(copperpour not_allowed)
				(footprints allowed)
			)
			(placement
				(enabled no)
				(sheetname "")
			)
			(fill
				(thermal_gap 0.5)
				(thermal_bridge_width 0.5)
				(island_removal_mode 0)
			)
			(polygon
				(pts
					(xy 368.808 -110.744) (xy 368.808 -111.252) (xy 369.189 -111.252) (xy 369.189 -110.744)
				)
			)
		)
		(zone
			(layer "F.Cu")
			(hatch none 0.5)
			(connect_pads
				(clearance 0)
			)
			(min_thickness 0.25)
			(keepout
				(tracks not_allowed)
				(vias allowed)
				(pads allowed)
				(copperpour not_allowed)
				(footprints allowed)
			)
			(placement
				(enabled no)
				(sheetname "")
			)
			(fill
				(thermal_gap 0.5)
				(thermal_bridge_width 0.5)
				(island_removal_mode 0)
			)
			(polygon
				(pts
					(xy 369.189 -110.744) (xy 369.189 -111.252) (xy 368.808 -111.252) (xy 368.808 -110.744)
				)
			)
		)
	)
	(footprint ""
		(layer "F.Cu")
		(at 364.78464 -141.77137)
		(property "Reference" "R7A7"
			(at 0 0 0)
			(layer "F.SilkS")
			(hide yes)
			(effects
				(font
					(size 1.27 1.27)
				)
			)
		)
		(property "Value" ""
			(at 0 0 0)
			(layer "F.Fab")
			(effects
				(font
					(size 1.27 1.27)
				)
			)
		)
		(duplicate_pad_numbers_are_jumpers no)
		(fp_poly
			(pts
				(xy -0.2794 -0.1016) (xy 0.2794 -0.1016) (xy 0.2794 0.9906) (xy -0.2794 0.9906)
			)
			(stroke
				(width 0)
				(type default)
			)
			(fill no)
			(layer "F.CrtYd")
		)
		(fp_line
			(start -0.2794 -0.1016)
			(end -0.2794 0.9906)
			(stroke
				(width 0.1)
				(type default)
			)
			(layer "F.Fab")
		)
		(fp_line
			(start -0.2794 0.9906)
			(end 0.2794 0.9906)
			(stroke
				(width 0.1)
				(type default)
			)
			(layer "F.Fab")
		)
		(fp_line
			(start 0.2794 -0.1016)
			(end -0.2794 -0.1016)
			(stroke
				(width 0.1)
				(type default)
			)
			(layer "F.Fab")
		)
		(fp_line
			(start 0.2794 0.9906)
			(end 0.2794 -0.1016)
			(stroke
				(width 0.1)
				(type default)
			)
			(layer "F.Fab")
		)
		(pad "1" smd rect
			(at 0 0)
			(size 0.508 0.508)
			(layers "F.Cu" "F.Mask" "F.Paste")
			(net "VSENSE_PVDDQ_DEF_P")
		)
		(pad "2" smd rect
			(at 0 0.889)
			(size 0.508 0.508)
			(layers "F.Cu" "F.Mask" "F.Paste")
			(net "VR_PVDDQ_DEF_AVSP")
		)
		(zone
			(layer "F.Cu")
			(hatch none 0.5)
			(connect_pads
				(clearance 0)
			)
			(min_thickness 0.25)
			(keepout
				(tracks allowed)
				(vias not_allowed)
				(pads allowed)
				(copperpour not_allowed)
				(footprints allowed)
			)
			(placement
				(enabled no)
				(sheetname "")
			)
			(fill
				(thermal_gap 0.5)
				(thermal_bridge_width 0.5)
				(island_removal_mode 0)
			)
			(polygon
				(pts
					(xy 364.53064 -141.51737) (xy 365.03864 -141.51737) (xy 365.03864 -141.13637) (xy 364.53064 -141.13637)
				)
			)
		)
		(zone
			(layer "F.Cu")
			(hatch none 0.5)
			(connect_pads
				(clearance 0)
			)
			(min_thickness 0.25)
			(keepout
				(tracks not_allowed)
				(vias allowed)
				(pads allowed)
				(copperpour not_allowed)
				(footprints allowed)
			)
			(placement
				(enabled no)
				(sheetname "")
			)
			(fill
				(thermal_gap 0.5)
				(thermal_bridge_width 0.5)
				(island_removal_mode 0)
			)
			(polygon
				(pts
					(xy 364.53064 -141.13637) (xy 365.03864 -141.13637) (xy 365.03864 -141.51737) (xy 364.53064 -141.51737)
				)
			)
		)
	)
	(footprint ""
		(layer "F.Cu")
		(at 101.3968 -140.208 90)
		(property "Reference" "C2A14"
			(at 1.848866 0.752348 90)
			(unlocked yes)
			(layer "F.SilkS")
			(effects
				(font
					(size 1.27 0.9652)
					(thickness 0.1524)
				)
			)
		)
		(property "Value" ""
			(at 0 0 90)
			(layer "F.Fab")
			(effects
				(font
					(size 1.27 1.27)
				)
			)
		)
		(duplicate_pad_numbers_are_jumpers no)
		(fp_rect
			(start -0.500126 1.598422)
			(end 0.500126 -0.201422)
			(stroke
				(width 0)
				(type default)
			)
			(fill no)
			(layer "F.CrtYd")
		)
		(fp_line
			(start 0.500126 -0.201422)
			(end 0.500126 1.598422)
			(stroke
				(width 0.1)
				(type default)
			)
			(layer "F.Fab")
		)
		(fp_line
			(start -0.500126 -0.201422)
			(end 0.500126 -0.201422)
			(stroke
				(width 0.1)
				(type default)
			)
			(layer "F.Fab")
		)
		(fp_line
			(start 0.500126 1.598422)
			(end -0.500126 1.598422)
			(stroke
				(width 0.1)
				(type default)
			)
			(layer "F.Fab")
		)
		(fp_line
			(start -0.500126 1.598422)
			(end -0.500126 -0.201422)
			(stroke
				(width 0.1)
				(type default)
			)
			(layer "F.Fab")
		)
		(pad "1" smd rect
			(at 0 0)
			(size 0.889 0.9906)
			(layers "F.Cu" "F.Mask" "F.Paste")
			(net "PVDDQ_KLM")
		)
		(pad "2" smd rect
			(at 0 1.397)
			(size 0.889 0.9906)
			(layers "F.Cu" "F.Mask" "F.Paste")
			(net "GND")
		)
		(zone
			(layer "F.Cu")
			(hatch none 0.5)
			(connect_pads
				(clearance 0)
			)
			(min_thickness 0.25)
			(keepout
				(tracks not_allowed)
				(vias allowed)
				(pads allowed)
				(copperpour not_allowed)
				(footprints allowed)
			)
			(placement
				(enabled no)
				(sheetname "")
			)
			(fill
				(thermal_gap 0.5)
				(thermal_bridge_width 0.5)
				(island_removal_mode 0)
			)
			(polygon
				(pts
					(xy 102.3493 -139.7127) (xy 102.3493 -140.7033) (xy 101.8413 -140.7033) (xy 101.8413 -139.7127)
				)
			)
		)
		(zone
			(layer "F.Cu")
			(hatch none 0.5)
			(connect_pads
				(clearance 0)
			)
			(min_thickness 0.25)
			(keepout
				(tracks allowed)
				(vias not_allowed)
				(pads allowed)
				(copperpour not_allowed)
				(footprints allowed)
			)
			(placement
				(enabled no)
				(sheetname "")
			)
			(fill
				(thermal_gap 0.5)
				(thermal_bridge_width 0.5)
				(island_removal_mode 0)
			)
			(polygon
				(pts
					(xy 102.3493 -139.7127) (xy 102.3493 -140.7033) (xy 101.8413 -140.7033) (xy 101.8413 -139.7127)
				)
			)
		)
	)
)
